# TIMECARD (Time Appliance Project (Time Card)) — schematic netlist excerpt (pin names and nets, part order shuffled) for the footprints in the layout excerpt that follows; sources: Cadence DE-HDL packaged netlist, KiCad conversion of R4006-B0001-02_R01.brd

C65  CAPACITOR  0.1UF 25V 10%  pkg SMC_0402R_H022  page 21 : \1\ = XP5R0V_MAC_USB ; \2\ = SG
R436  RESISTOR  15KOHM 1%  pkg SMC_0402R_H016  page 11 : \1\ = SG ; \2\ = MAC_USB_DP

(kicad_pcb
	(version 20260206)
	(generator "pcbnew")
	(generator_version "10.0")
	(general
		(thickness 1.6)
		(legacy_teardrops no)
	)
	(paper "A4")
	(title_block
		(title "timecard-production-celestica-r4006 — R4006-B0001-02_R01.brd")
		(comment 1 "Time Appliance Project (Time Card) / footprints 1023-1024 of 1113")
	)
	(layers
		(0 "F.Cu" signal "TOP")
		(4 "In1.Cu" signal "L02_GND1")
		(6 "In2.Cu" signal "L03_SIG1")
		(8 "In3.Cu" signal "L04_GND2")
		(10 "In4.Cu" signal "L05_VCC1")
		(12 "In5.Cu" signal "L06_VCC2")
		(14 "In6.Cu" signal "L07_GND3")
		(16 "In7.Cu" signal "L08_SIG2")
		(18 "In8.Cu" signal "L09_GND4")
		(2 "B.Cu" signal "BOTTOM")
		(9 "F.Adhes" user "F.Adhesive")
		(11 "B.Adhes" user "B.Adhesive")
		(13 "F.Paste" user "Package Geometry/Pastemask Top")
		(15 "B.Paste" user "Package Geometry/Pastemask Bottom")
		(5 "F.SilkS" user "Ref Des/Silkscreen Top")
		(7 "B.SilkS" user "Ref Des/Silkscreen Bottom")
		(1 "F.Mask" user "Board Geometry/Soldermask Top")
		(3 "B.Mask" user "Board Geometry/Soldermask Bottom")
		(17 "Dwgs.User" user "User.Drawings")
		(19 "Cmts.User" user "User.Comments")
		(21 "Eco1.User" user "User.Eco1")
		(23 "Eco2.User" user "User.Eco2")
		(25 "Edge.Cuts" user "Board Geometry/Outline")
		(27 "Margin" user)
		(31 "F.CrtYd" user "Package Geometry/Place Bound Top")
		(29 "B.CrtYd" user "Package Geometry/Place Bound Bottom")
		(35 "F.Fab" user "Ref Des/Assembly Top")
		(33 "B.Fab" user "Ref Des/Assembly Bottom")
	)
	(footprint ""
		(layer "B.Cu")
		(at 76.708 -50.927 180)
		(property "Reference" "C65"
			(at -3.175 0.08763 0)
			(unlocked yes)
			(layer "B.SilkS")
			(effects
				(font
					(size 0.7874 0.5842)
					(thickness 0.1524)
				)
				(justify mirror)
			)
		)
		(property "Value" "VAL*"
			(at -0.0762 2.067306 180)
			(unlocked yes)
			(layer "B.Fab")
			(hide yes)
			(effects
				(font
					(size 0.7874 0.5842)
					(thickness 0.1524)
				)
				(justify mirror)
			)
		)
		(property "Tolerance" "TOL*"
			(at -0.0762 3.032506 180)
			(unlocked yes)
			(layer "Cmts.User")
			(hide yes)
			(effects
				(font
					(size 0.7874 0.5842)
					(thickness 0.1524)
				)
				(justify mirror)
			)
		)
		(property "User Part Number" "PARTNUM*"
			(at -0.1016 4.023106 180)
			(unlocked yes)
			(layer "Cmts.User")
			(hide yes)
			(effects
				(font
					(size 0.7874 0.5842)
					(thickness 0.1524)
				)
				(justify mirror)
			)
		)
		(property "Device Type" "CAPACITOR-G105-0B104-EK,0.1UF,A"
			(at -0.0508 1.127506 180)
			(unlocked yes)
			(layer "B.Fab")
			(hide yes)
			(effects
				(font
					(size 0.7874 0.5842)
					(thickness 0.1524)
				)
				(justify mirror)
			)
		)
		(duplicate_pad_numbers_are_jumpers no)
		(fp_line
			(start 1.143 0.5588)
			(end -1.143 0.5588)
			(stroke
				(width 0.1)
				(type default)
			)
			(layer "B.SilkS")
		)
		(fp_line
			(start 1.143 -0.5588)
			(end 1.143 0.5588)
			(stroke
				(width 0.1)
				(type default)
			)
			(layer "B.SilkS")
		)
		(fp_line
			(start -1.143 0.5588)
			(end -1.143 -0.5588)
			(stroke
				(width 0.1)
				(type default)
			)
			(layer "B.SilkS")
		)
		(fp_line
			(start -1.143 -0.5588)
			(end 1.143 -0.5588)
			(stroke
				(width 0.1)
				(type default)
			)
			(layer "B.SilkS")
		)
		(fp_rect
			(start 1.143 0.5588)
			(end -1.143 -0.5588)
			(stroke
				(width 0)
				(type default)
			)
			(fill no)
			(layer "B.CrtYd")
		)
		(fp_line
			(start 0.508 0.3048)
			(end -0.508 0.3048)
			(stroke
				(width 0.1)
				(type default)
			)
			(layer "B.Fab")
		)
		(fp_line
			(start 0.508 -0.3048)
			(end 0.508 0.3048)
			(stroke
				(width 0.1)
				(type default)
			)
			(layer "B.Fab")
		)
		(fp_line
			(start -0.508 0.3048)
			(end -0.508 -0.3048)
			(stroke
				(width 0.1)
				(type default)
			)
			(layer "B.Fab")
		)
		(fp_line
			(start -0.508 -0.3048)
			(end 0.508 -0.3048)
			(stroke
				(width 0.1)
				(type default)
			)
			(layer "B.Fab")
		)
		(pad "1" smd rect
			(at 0.5334 0)
			(size 0.7112 0.6096)
			(layers "B.Cu" "B.Mask" "B.Paste")
			(net "XP5R0V_MAC_USB")
		)
		(pad "2" smd rect
			(at -0.5334 0)
			(size 0.7112 0.6096)
			(layers "B.Cu" "B.Mask" "B.Paste")
			(net "SG")
		)
		(zone
			(layer "B.Cu")
			(hatch none 0.5)
			(connect_pads
				(clearance 0)
			)
			(min_thickness 0.25)
			(keepout
				(tracks allowed)
				(vias not_allowed)
				(pads allowed)
				(copperpour not_allowed)
				(footprints allowed)
			)
			(placement
				(enabled no)
				(sheetname "")
			)
			(fill
				(thermal_gap 0.5)
				(thermal_bridge_width 0.5)
				(island_removal_mode 0)
			)
			(polygon
				(pts
					(xy 76.6318 -51.2318) (xy 76.6318 -50.6222) (xy 76.7842 -50.6222) (xy 76.7842 -51.2318)
				)
			)
		)
	)
	(footprint ""
		(layer "B.Cu")
		(at 112.84712 -46.322996 -90)
		(property "Reference" "R436"
			(at 2.032 43.029886 270)
			(unlocked yes)
			(layer "B.SilkS")
			(effects
				(font
					(size 0.635 0.4064)
					(thickness 0.1524)
				)
				(justify mirror)
			)
		)
		(property "Value" "VAL*"
			(at 0 3.718306 270)
			(unlocked yes)
			(layer "B.Fab")
			(hide yes)
			(effects
				(font
					(size 0.7874 0.5842)
					(thickness 0.127)
				)
				(justify mirror)
			)
		)
		(property "Tolerance" "TOL*"
			(at 0 4.861306 270)
			(unlocked yes)
			(layer "Cmts.User")
			(hide yes)
			(effects
				(font
					(size 0.7874 0.5842)
					(thickness 0.127)
				)
				(justify mirror)
			)
		)
		(property "User Part Number" "PARTNUM*"
			(at 0 2.575306 270)
			(unlocked yes)
			(layer "Cmts.User")
			(hide yes)
			(effects
				(font
					(size 0.7874 0.5842)
					(thickness 0.127)
				)
				(justify mirror)
			)
		)
		(property "Device Type" "RESISTOR-G155-11502-01,15KOHM,A"
			(at 0 1.432306 270)
			(unlocked yes)
			(layer "B.Fab")
			(hide yes)
			(effects
				(font
					(size 0.7874 0.5842)
					(thickness 0.127)
				)
				(justify mirror)
			)
		)
		(duplicate_pad_numbers_are_jumpers no)
		(fp_line
			(start -0.970026 0.4699)
			(end 0.970026 0.4699)
			(stroke
				(width 0.1)
				(type default)
			)
			(layer "B.SilkS")
		)
		(fp_line
			(start 0.970026 0.4699)
			(end 0.970026 -0.4699)
			(stroke
				(width 0.1)
				(type default)
			)
			(layer "B.SilkS")
		)
		(fp_line
			(start -0.970026 -0.4699)
			(end -0.970026 0.4699)
			(stroke
				(width 0.1)
				(type default)
			)
			(layer "B.SilkS")
		)
		(fp_line
			(start 0.970026 -0.4699)
			(end -0.970026 -0.4699)
			(stroke
				(width 0.1)
				(type default)
			)
			(layer "B.SilkS")
		)
		(fp_poly
			(pts
				(xy 0.970026 0.4699) (xy -0.970026 0.4699) (xy -0.970026 -0.4699) (xy 0.970026 -0.4699)
			)
			(stroke
				(width 0)
				(type default)
			)
			(fill no)
			(layer "B.CrtYd")
		)
		(fp_line
			(start -0.508 0.3048)
			(end 0.508 0.3048)
			(stroke
				(width 0.1)
				(type default)
			)
			(layer "B.Fab")
		)
		(fp_line
			(start 0.508 0.3048)
			(end 0.508 -0.3048)
			(stroke
				(width 0.1)
				(type default)
			)
			(layer "B.Fab")
		)
		(fp_line
			(start -0.508 -0.3048)
			(end -0.508 0.3048)
			(stroke
				(width 0.1)
				(type default)
			)
			(layer "B.Fab")
		)
		(fp_line
			(start 0.508 -0.3048)
			(end -0.508 -0.3048)
			(stroke
				(width 0.1)
				(type default)
			)
			(layer "B.Fab")
		)
		(pad "1" smd circle
			(at 0.500126 0 90)
			(size 0.635 0.635)
			(layers "B.Cu" "B.Mask" "B.Paste")
			(net "SG")
		)
		(pad "2" smd circle
			(at -0.500126 0 90)
			(size 0.635 0.635)
			(layers "B.Cu" "B.Mask" "B.Paste")
			(net "MAC_USB_DP")
		)
	)
)
